FILE_TYPE = CONNECTIVITY;
{Allegro Design Entry HDL 16.6-p007 (v16-6-112F) 10/10/2012}
"PAGE_NUMBER" = 244;
0"NC";
1"P3E_CPU0_PE1_PCH_RXP<15:8>";
2"P3E_CPU0_PE1_PCH_CON_RXN<15:8>";
3"P3E_CPU0_PE1_PCH_CON_TXN<15:8>";
4"P3E_CPU0_PE1_PCH_RXN<15:8>";
5"P3E_CPU0_PE1_PCH_CON_RXP<15:8>";
6"P3E_CPU0_PE1_PCH_CON_TXP<15:8>";
7"P3E_CPU0_PE1_PCH_TXP<15:8>";
8"P3E_CPU0_PE1_PCH_TXN<15:8>";
9"P3E_CPU0_PE1_PCH_CON_RXN<12>";
10"P3E_CPU0_PE1_PCH_CON_TXN<13>";
11"P3E_CPU0_PE1_PCH_CON_TXN<8>";
12"P3E_CPU0_PE1_PCH_TXP<9>";
13"P3E_CPU0_PE1_PCH_CON_TXP<10>";
14"P3E_CPU0_PE1_PCH_RXP<15>";
15"P3E_CPU0_PE1_PCH_TXP<15>";
16"P3E_CPU0_PE1_PCH_CON_TXN<11>";
17"P3E_CPU0_PE1_PCH_CON_RXP<9>";
18"P3E_CPU0_PE1_PCH_CON_RXP<14>";
19"P3E_CPU0_PE1_PCH_CON_RXN<15>";
20"P3E_CPU0_PE1_PCH_CON_RXN<10>";
21"P3E_CPU0_PE1_PCH_CON_RXN<9>";
22"P3E_CPU0_PE1_PCH_CON_RXN<8>";
23"P3E_CPU0_PE1_PCH_RXN<9>";
24"P3E_CPU0_PE1_PCH_RXN<13>";
25"P3E_CPU0_PE1_PCH_CON_RXN<14>";
26"P3E_CPU0_PE1_PCH_RXN<8>";
27"P3E_CPU0_PE1_PCH_RXN<11>";
28"P3E_CPU0_PE1_PCH_CON_RXP<12>";
29"P3E_CPU0_PE1_PCH_RXP<11>";
30"P3E_CPU0_PE1_PCH_CON_RXP<10>";
31"P3E_CPU0_PE1_PCH_TXN<15>";
32"P3E_CPU0_PE1_PCH_TXP<12>";
33"P3E_CPU0_PE1_PCH_TXN<10>";
34"P3E_CPU0_PE1_PCH_TXN<8>";
35"P3E_CPU0_PE1_PCH_TXN<9>";
36"P3E_CPU0_PE1_PCH_TXP<10>";
37"P3E_CPU0_PE1_PCH_TXN<12>";
38"P3E_CPU0_PE1_PCH_TXN<13>";
39"P3E_CPU0_PE1_PCH_TXN<14>";
40"P3E_CPU0_PE1_PCH_CON_TXN<15>";
41"P3E_CPU0_PE1_PCH_CON_TXP<14>";
42"P3E_CPU0_PE1_PCH_CON_TXP<13>";
43"P3E_CPU0_PE1_PCH_CON_TXP<15>";
44"P3E_CPU0_PE1_PCH_CON_TXN<14>";
45"P3E_CPU0_PE1_PCH_CON_TXN<12>";
46"P3E_CPU0_PE1_PCH_TXN<11>";
47"P3E_CPU0_PE1_PCH_CON_TXN<9>";
48"P3E_CPU0_PE1_PCH_RXN<14>";
49"P3E_CPU0_PE1_PCH_RXN<10>";
50"P3E_CPU0_PE1_PCH_RXN<12>";
51"P3E_CPU0_PE1_PCH_TXP<8>";
52"P3E_CPU0_PE1_PCH_TXP<13>";
53"P3E_CPU0_PE1_PCH_CON_TXP<8>";
54"P3E_CPU0_PE1_PCH_TXP<11>";
55"P3E_CPU0_PE1_PCH_TXP<14>";
56"P3E_CPU0_PE1_PCH_CON_TXP<11>";
57"P3E_CPU0_PE1_PCH_CON_TXP<12>";
58"P3E_CPU0_PE1_PCH_CON_TXP<9>";
59"P3E_CPU0_PE1_PCH_CON_RXP<13>";
60"P3E_CPU0_PE1_PCH_CON_RXP<15>";
61"P3E_CPU0_PE1_PCH_RXP<14>";
62"P3E_CPU0_PE1_PCH_RXP<12>";
63"P3E_CPU0_PE1_PCH_CON_RXP<11>";
64"P3E_CPU0_PE1_PCH_RXP<10>";
65"P3E_CPU0_PE1_PCH_RXP<9>";
66"P3E_CPU0_PE1_PCH_CON_RXP<8>";
67"P3E_CPU0_PE1_PCH_RXP<8>";
68"P3E_CPU0_PE1_PCH_RXN<15>";
69"P3E_CPU0_PE1_PCH_CON_RXN<13>";
70"P3E_CPU0_PE1_PCH_CON_TXN<10>";
71"P3E_CPU0_PE1_PCH_CON_RXN<11>";
72"P3E_CPU0_PE1_PCH_RXP<13>";
%"TAP"
"7","(-5925,1475)","0","mstr_standard","I1";
;
CDS_LIB"mstr_standard"
BODY_TYPE"PLUMBING"
HDL_TAP"TRUE";
"B \NAC \NWC"6;
"S \NAC"
BN"15"43;
%"TAP"
"3","(-2500,3575)","0","mstr_standard","I100";
;
CDS_LIB"mstr_standard"
BODY_TYPE"PLUMBING"
HDL_TAP"TRUE";
"B \NAC \NWC"4;
"S \NAC"
BN"10"49;
%"TAP"
"3","(-2300,3575)","0","mstr_standard","I101";
;
CDS_LIB"mstr_standard"
BODY_TYPE"PLUMBING"
HDL_TAP"TRUE";
"B \NAC \NWC"4;
"S \NAC"
BN"9"23;
%"TAP"
"3","(-2100,3575)","0","mstr_standard","I102";
;
CDS_LIB"mstr_standard"
BODY_TYPE"PLUMBING"
HDL_TAP"TRUE";
"B \NAC \NWC"4;
"S \NAC"
BN"8"26;
%"RES"
"2","(-2025,2075)","0","mstr_discrete","I103";
;
CDS_SEC"1"
MATERIAL"CHIP"
PACK_TYPE"0402"
PART_NUMBER"G21497-005"
WATTAGE"1/16W"
TOLERANCE"5%"
VALUE"0.0"
$LOCATION"R785"
GROUP"PCIE_RISER"
CDS_LOCATION"R785"
CDS_LIB"mstr_discrete"
ROOM"PCIE_STEERING"
SEC"1"
SEC_TYPE"0402";
"A"
$PN"1"67;
"B"
$PN"2"66;
%"TAP"
"3","(-5925,2275)","0","mstr_standard","I11";
;
CDS_LIB"mstr_standard"
BODY_TYPE"PLUMBING"
HDL_TAP"TRUE";
"B \NAC \NWC"7;
"S \NAC"
BN"15"15;
%"CAP"
"1","(-5725,2025)","2","mstr_discrete","I12";
;
CDS_SEC"1"
$LOCATION"C827"
VOLTAGE"16V"
PART_NUMBER"A36096-155"
PACK_TYPE"0402"
VALUE"0.22UF"
TOLERANCE"10%"
MATERIAL"X7R"
GROUP"PCIE_RISER"
CDS_LOCATION"C827"
CDS_LIB"mstr_discrete"
ROOM"OCP_STEERING"
SEC"1"
SEC_TYPE"0402";
"A"
$PN"1"55;
"B"
$PN"2"41;
%"TAP"
"3","(-5725,2275)","0","mstr_standard","I13";
;
CDS_LIB"mstr_standard"
BODY_TYPE"PLUMBING"
HDL_TAP"TRUE";
"B \NAC \NWC"7;
"S \NAC"
BN"14"55;
%"TAP"
"7","(-6025,2775)","0","mstr_standard","I14";
;
CDS_LIB"mstr_standard"
BODY_TYPE"PLUMBING"
HDL_TAP"TRUE";
"B \NAC \NWC"3;
"S \NAC"
BN"15"40;
%"TAP"
"7","(-5825,2775)","0","mstr_standard","I15";
;
CDS_LIB"mstr_standard"
BODY_TYPE"PLUMBING"
HDL_TAP"TRUE";
"B \NAC \NWC"3;
"S \NAC"
BN"14"44;
%"TAP"
"3","(-5525,2275)","0","mstr_standard","I16";
;
CDS_LIB"mstr_standard"
BODY_TYPE"PLUMBING"
HDL_TAP"TRUE";
"B \NAC \NWC"7;
"S \NAC"
BN"13"52;
%"CAP"
"1","(-5325,2025)","2","mstr_discrete","I17";
;
CDS_SEC"1"
VALUE"0.22UF"
$LOCATION"C841"
VOLTAGE"16V"
PART_NUMBER"A36096-155"
TOLERANCE"10%"
PACK_TYPE"0402"
MATERIAL"X7R"
GROUP"PCIE_RISER"
CDS_LOCATION"C841"
CDS_LIB"mstr_discrete"
ROOM"OCP_STEERING"
SEC"1"
SEC_TYPE"0402";
"A"
$PN"1"32;
"B"
$PN"2"57;
%"TAP"
"3","(-5325,2275)","0","mstr_standard","I18";
;
CDS_LIB"mstr_standard"
BODY_TYPE"PLUMBING"
HDL_TAP"TRUE";
"B \NAC \NWC"7;
"S \NAC"
BN"12"32;
%"TAP"
"3","(-5125,2275)","0","mstr_standard","I19";
;
CDS_LIB"mstr_standard"
BODY_TYPE"PLUMBING"
HDL_TAP"TRUE";
"B \NAC \NWC"7;
"S \NAC"
BN"11"54;
%"CAP"
"1","(-5925,1725)","2","mstr_discrete","I2";
;
CDS_SEC"1"
MATERIAL"X7R"
TOLERANCE"10%"
PART_NUMBER"A36096-155"
$LOCATION"C831"
VOLTAGE"16V"
PACK_TYPE"0402"
VALUE"0.22UF"
GROUP"PCIE_RISER"
CDS_LOCATION"C831"
CDS_LIB"mstr_discrete"
ROOM"OCP_STEERING"
SEC"1"
SEC_TYPE"0402";
"A"
$PN"1"15;
"B"
$PN"2"43;
%"TAP"
"7","(-5625,2775)","0","mstr_standard","I20";
;
CDS_LIB"mstr_standard"
BODY_TYPE"PLUMBING"
HDL_TAP"TRUE";
"B \NAC \NWC"3;
"S \NAC"
BN"13"10;
%"TAP"
"7","(-5425,2775)","0","mstr_standard","I21";
;
CDS_LIB"mstr_standard"
BODY_TYPE"PLUMBING"
HDL_TAP"TRUE";
"B \NAC \NWC"3;
"S \NAC"
BN"12"45;
%"TAP"
"7","(-5225,2775)","0","mstr_standard","I22";
;
CDS_LIB"mstr_standard"
BODY_TYPE"PLUMBING"
HDL_TAP"TRUE";
"B \NAC \NWC"3;
"S \NAC"
BN"11"16;
%"CAP"
"1","(-6025,3025)","2","mstr_discrete","I23";
;
CDS_SEC"1"
PACK_TYPE"0402"
$LOCATION"C830"
VALUE"0.22UF"
MATERIAL"X7R"
VOLTAGE"16V"
PART_NUMBER"A36096-155"
TOLERANCE"10%"
GROUP"PCIE_RISER"
SEC_TYPE"0402"
SEC"1"
CDS_LOCATION"C830"
ROOM"OCP_STEERING"
CDS_LIB"mstr_discrete";
"A"
$PN"1"31;
"B"
$PN"2"40;
%"CAP"
"1","(-5825,3325)","2","mstr_discrete","I24";
;
CDS_SEC"1"
PACK_TYPE"0402"
VALUE"0.22UF"
VOLTAGE"16V"
TOLERANCE"10%"
MATERIAL"X7R"
PART_NUMBER"A36096-155"
$LOCATION"C826"
GROUP"PCIE_RISER"
SEC_TYPE"0402"
SEC"1"
CDS_LOCATION"C826"
ROOM"OCP_STEERING"
CDS_LIB"mstr_discrete";
"A"
$PN"1"39;
"B"
$PN"2"44;
%"TAP"
"3","(-6025,3575)","0","mstr_standard","I25";
;
CDS_LIB"mstr_standard"
BODY_TYPE"PLUMBING"
HDL_TAP"TRUE";
"B \NAC \NWC"8;
"S \NAC"
BN"15"31;
%"TAP"
"3","(-5825,3575)","0","mstr_standard","I26";
;
CDS_LIB"mstr_standard"
BODY_TYPE"PLUMBING"
HDL_TAP"TRUE";
"B \NAC \NWC"8;
"S \NAC"
BN"14"39;
%"TAP"
"3","(-5625,3575)","0","mstr_standard","I27";
;
CDS_LIB"mstr_standard"
BODY_TYPE"PLUMBING"
HDL_TAP"TRUE";
"B \NAC \NWC"8;
"S \NAC"
BN"13"38;
%"CAP"
"1","(-5625,3025)","2","mstr_discrete","I28";
;
CDS_SEC"1"
PACK_TYPE"0402"
VALUE"0.22UF"
TOLERANCE"10%"
$LOCATION"C828"
VOLTAGE"16V"
MATERIAL"X7R"
PART_NUMBER"A36096-155"
GROUP"PCIE_RISER"
SEC_TYPE"0402"
SEC"1"
CDS_LOCATION"C828"
CDS_LIB"mstr_discrete"
ROOM"OCP_STEERING";
"A"
$PN"1"38;
"B"
$PN"2"10;
%"CAP"
"1","(-5425,3325)","2","mstr_discrete","I29";
;
CDS_SEC"1"
PACK_TYPE"0402"
$LOCATION"C840"
VOLTAGE"16V"
TOLERANCE"10%"
PART_NUMBER"A36096-155"
VALUE"0.22UF"
MATERIAL"X7R"
GROUP"PCIE_RISER"
SEC_TYPE"0402"
SEC"1"
CDS_LOCATION"C840"
CDS_LIB"mstr_discrete"
ROOM"OCP_STEERING";
"A"
$PN"1"37;
"B"
$PN"2"45;
%"TAP"
"7","(-5725,1475)","0","mstr_standard","I3";
;
CDS_LIB"mstr_standard"
BODY_TYPE"PLUMBING"
HDL_TAP"TRUE";
"B \NAC \NWC"6;
"S \NAC"
BN"14"41;
%"CAP"
"1","(-5225,3025)","2","mstr_discrete","I30";
;
CDS_SEC"1"
VOLTAGE"16V"
VALUE"0.22UF"
$LOCATION"C832"
TOLERANCE"10%"
MATERIAL"X7R"
PART_NUMBER"A36096-155"
PACK_TYPE"0402"
GROUP"PCIE_RISER"
SEC_TYPE"0402"
SEC"1"
CDS_LOCATION"C832"
CDS_LIB"mstr_discrete"
ROOM"OCP_STEERING";
"A"
$PN"1"46;
"B"
$PN"2"16;
%"TAP"
"3","(-5425,3575)","0","mstr_standard","I31";
;
CDS_LIB"mstr_standard"
BODY_TYPE"PLUMBING"
HDL_TAP"TRUE";
"B \NAC \NWC"8;
"S \NAC"
BN"12"37;
%"TAP"
"3","(-5225,3575)","0","mstr_standard","I32";
;
CDS_LIB"mstr_standard"
BODY_TYPE"PLUMBING"
HDL_TAP"TRUE";
"B \NAC \NWC"8;
"S \NAC"
BN"11"46;
%"TAP"
"7","(-4925,1475)","0","mstr_standard","I33";
;
CDS_LIB"mstr_standard"
BODY_TYPE"PLUMBING"
HDL_TAP"TRUE";
"B \NAC \NWC"6;
"S \NAC"
BN"10"13;
%"TAP"
"7","(-4725,1475)","0","mstr_standard","I34";
;
CDS_LIB"mstr_standard"
BODY_TYPE"PLUMBING"
HDL_TAP"TRUE";
"B \NAC \NWC"6;
"S \NAC"
BN"9"58;
%"CAP"
"1","(-4725,1725)","2","mstr_discrete","I35";
;
CDS_SEC"1"
PART_NUMBER"A36096-155"
MATERIAL"X7R"
TOLERANCE"10%"
$LOCATION"C845"
VALUE"0.22UF"
VOLTAGE"16V"
PACK_TYPE"0402"
GROUP"PCIE_RISER"
CDS_LOCATION"C845"
CDS_LIB"mstr_discrete"
ROOM"OCP_STEERING"
SEC"1"
SEC_TYPE"0402";
"A"
$PN"1"12;
"B"
$PN"2"58;
%"TAP"
"7","(-4525,1475)","0","mstr_standard","I36";
;
CDS_LIB"mstr_standard"
BODY_TYPE"PLUMBING"
HDL_TAP"TRUE";
"B \NAC \NWC"6;
"S \NAC"
BN"8"53;
%"TAP"
"7","(-3425,1475)","0","mstr_standard","I38";
;
CDS_LIB"mstr_standard"
BODY_TYPE"PLUMBING"
HDL_TAP"TRUE";
"B \NAC \NWC"5;
"S \NAC"
BN"15"60;
%"RES"
"2","(-3425,1725)","0","mstr_discrete","I39";
;
CDS_SEC"1"
WATTAGE"1/16W"
TOLERANCE"5%"
MATERIAL"CHIP"
VALUE"0.0"
PACK_TYPE"0402"
$LOCATION"R767"
PART_NUMBER"G21497-005"
GROUP"PCIE_RISER"
CDS_LOCATION"R767"
CDS_LIB"mstr_discrete"
ROOM"PCIE_STEERING"
SEC"1"
SEC_TYPE"0402";
"A"
$PN"1"14;
"B"
$PN"2"60;
%"TAP"
"7","(-5525,1475)","0","mstr_standard","I4";
;
CDS_LIB"mstr_standard"
BODY_TYPE"PLUMBING"
HDL_TAP"TRUE";
"B \NAC \NWC"6;
"S \NAC"
BN"13"42;
%"TAP"
"7","(-3225,1475)","0","mstr_standard","I40";
;
CDS_LIB"mstr_standard"
BODY_TYPE"PLUMBING"
HDL_TAP"TRUE";
"B \NAC \NWC"5;
"S \NAC"
BN"14"18;
%"CAP"
"1","(-4925,2025)","2","mstr_discrete","I41";
;
CDS_SEC"1"
PACK_TYPE"0402"
$LOCATION"C835"
VALUE"0.22UF"
VOLTAGE"16V"
TOLERANCE"10%"
MATERIAL"X7R"
PART_NUMBER"A36096-155"
GROUP"PCIE_RISER"
CDS_LOCATION"C835"
CDS_LIB"mstr_discrete"
ROOM"OCP_STEERING"
SEC"1"
SEC_TYPE"0402";
"A"
$PN"1"36;
"B"
$PN"2"13;
%"TAP"
"3","(-4925,2275)","0","mstr_standard","I42";
;
CDS_LIB"mstr_standard"
BODY_TYPE"PLUMBING"
HDL_TAP"TRUE";
"B \NAC \NWC"7;
"S \NAC"
BN"10"36;
%"TAP"
"3","(-4725,2275)","0","mstr_standard","I43";
;
CDS_LIB"mstr_standard"
BODY_TYPE"PLUMBING"
HDL_TAP"TRUE";
"B \NAC \NWC"7;
"S \NAC"
BN"9"12;
%"TAP"
"7","(-5025,2775)","0","mstr_standard","I44";
;
CDS_LIB"mstr_standard"
BODY_TYPE"PLUMBING"
HDL_TAP"TRUE";
"B \NAC \NWC"3;
"S \NAC"
BN"10"70;
%"TAP"
"7","(-4825,2775)","0","mstr_standard","I45";
;
CDS_LIB"mstr_standard"
BODY_TYPE"PLUMBING"
HDL_TAP"TRUE";
"B \NAC \NWC"3;
"S \NAC"
BN"9"47;
%"TAP"
"7","(-4625,2775)","0","mstr_standard","I46";
;
CDS_LIB"mstr_standard"
BODY_TYPE"PLUMBING"
HDL_TAP"TRUE";
"B \NAC \NWC"3;
"S \NAC"
BN"8"11;
%"CAP"
"1","(-4525,2025)","2","mstr_discrete","I47";
;
CDS_SEC"1"
PACK_TYPE"0402"
PART_NUMBER"A36096-155"
MATERIAL"X7R"
TOLERANCE"10%"
VALUE"0.22UF"
VOLTAGE"16V"
$LOCATION"C843"
GROUP"PCIE_RISER"
CDS_LOCATION"C843"
CDS_LIB"mstr_discrete"
ROOM"OCP_STEERING"
SEC"1"
SEC_TYPE"0402";
"A"
$PN"1"51;
"B"
$PN"2"53;
%"TAP"
"3","(-4525,2275)","0","mstr_standard","I48";
;
CDS_LIB"mstr_standard"
BODY_TYPE"PLUMBING"
HDL_TAP"TRUE";
"B \NAC \NWC"7;
"S \NAC"
BN"8"51;
%"CAP"
"1","(-5525,1725)","2","mstr_discrete","I5";
;
CDS_SEC"1"
TOLERANCE"10%"
VOLTAGE"16V"
MATERIAL"X7R"
VALUE"0.22UF"
$LOCATION"C829"
PACK_TYPE"0402"
PART_NUMBER"A36096-155"
GROUP"PCIE_RISER"
CDS_LOCATION"C829"
CDS_LIB"mstr_discrete"
ROOM"OCP_STEERING"
SEC"1"
SEC_TYPE"0402";
"A"
$PN"1"52;
"B"
$PN"2"42;
%"CAP"
"1","(-5025,3325)","2","mstr_discrete","I50";
;
CDS_SEC"1"
PACK_TYPE"0402"
TOLERANCE"10%"
MATERIAL"X7R"
PART_NUMBER"A36096-155"
$LOCATION"C834"
VALUE"0.22UF"
VOLTAGE"16V"
GROUP"PCIE_RISER"
SEC_TYPE"0402"
SEC"1"
CDS_LOCATION"C834"
ROOM"OCP_STEERING"
CDS_LIB"mstr_discrete";
"A"
$PN"1"33;
"B"
$PN"2"70;
%"CAP"
"1","(-4825,3025)","2","mstr_discrete","I51";
;
CDS_SEC"1"
PACK_TYPE"0402"
VALUE"0.22UF"
MATERIAL"X7R"
TOLERANCE"10%"
$LOCATION"C844"
VOLTAGE"16V"
PART_NUMBER"A36096-155"
GROUP"PCIE_RISER"
SEC_TYPE"0402"
SEC"1"
CDS_LOCATION"C844"
ROOM"OCP_STEERING"
CDS_LIB"mstr_discrete";
"A"
$PN"1"35;
"B"
$PN"2"47;
%"CAP"
"1","(-4625,3300)","2","mstr_discrete","I52";
;
CDS_SEC"1"
PACK_TYPE"0402"
VOLTAGE"16V"
VALUE"0.22UF"
TOLERANCE"10%"
MATERIAL"X7R"
PART_NUMBER"A36096-155"
$LOCATION"C842"
GROUP"PCIE_RISER"
SEC_TYPE"0402"
SEC"1"
CDS_LOCATION"C842"
ROOM"OCP_STEERING"
CDS_LIB"mstr_discrete";
"A"
$PN"1"34;
"B"
$PN"2"11;
%"TAP"
"3","(-5025,3575)","0","mstr_standard","I53";
;
CDS_LIB"mstr_standard"
BODY_TYPE"PLUMBING"
HDL_TAP"TRUE";
"B \NAC \NWC"8;
"S \NAC"
BN"10"33;
%"TAP"
"3","(-4825,3575)","0","mstr_standard","I54";
;
CDS_LIB"mstr_standard"
BODY_TYPE"PLUMBING"
HDL_TAP"TRUE";
"B \NAC \NWC"8;
"S \NAC"
BN"9"35;
%"TAP"
"3","(-4625,3575)","0","mstr_standard","I55";
;
CDS_LIB"mstr_standard"
BODY_TYPE"PLUMBING"
HDL_TAP"TRUE";
"B \NAC \NWC"8;
"S \NAC"
BN"8"34;
%"TAP"
"3","(-3425,2275)","0","mstr_standard","I57";
;
CDS_LIB"mstr_standard"
BODY_TYPE"PLUMBING"
HDL_TAP"TRUE";
"B \NAC \NWC"1;
"S \NAC"
BN"15"14;
%"RES"
"2","(-3225,2075)","0","mstr_discrete","I58";
;
CDS_SEC"1"
GROUP"PCIE_RISER"
PART_NUMBER"G21497-005"
VALUE"0.0"
TOLERANCE"5%"
MATERIAL"CHIP"
PACK_TYPE"0402"
$LOCATION"R769"
WATTAGE"1/16W"
CDS_LOCATION"R769"
CDS_LIB"mstr_discrete"
ROOM"PCIE_STEERING"
SEC_TYPE"0402"
SEC"1";
"A"
$PN"1"61;
"B"
$PN"2"18;
%"TAP"
"3","(-3225,2275)","0","mstr_standard","I59";
;
CDS_LIB"mstr_standard"
BODY_TYPE"PLUMBING"
HDL_TAP"TRUE";
"B \NAC \NWC"1;
"S \NAC"
BN"14"61;
%"TAP"
"7","(-5325,1475)","0","mstr_standard","I6";
;
CDS_LIB"mstr_standard"
BODY_TYPE"PLUMBING"
HDL_TAP"TRUE";
"B \NAC \NWC"6;
"S \NAC"
BN"12"57;
%"TAP"
"7","(-3500,2775)","0","mstr_standard","I60";
;
CDS_LIB"mstr_standard"
BODY_TYPE"PLUMBING"
HDL_TAP"TRUE";
"B \NAC \NWC"2;
"S \NAC"
BN"15"19;
%"TAP"
"7","(-3300,2775)","0","mstr_standard","I61";
;
CDS_LIB"mstr_standard"
BODY_TYPE"PLUMBING"
HDL_TAP"TRUE";
"B \NAC \NWC"2;
"S \NAC"
BN"14"25;
%"TAP"
"7","(-3100,2775)","0","mstr_standard","I62";
;
CDS_LIB"mstr_standard"
BODY_TYPE"PLUMBING"
HDL_TAP"TRUE";
"B \NAC \NWC"2;
"S \NAC"
BN"13"69;
%"RES"
"2","(-3500,3025)","0","mstr_discrete","I64";
;
CDS_SEC"1"
GROUP"PCIE_RISER"
PART_NUMBER"G21497-005"
MATERIAL"CHIP"
WATTAGE"1/16W"
$LOCATION"R760"
VALUE"0.0"
TOLERANCE"5%"
PACK_TYPE"0402"
SEC_TYPE"0402"
SEC"1"
CDS_LOCATION"R760"
CDS_LIB"mstr_discrete"
ROOM"PCIE_STEERING";
"A"
$PN"1"68;
"B"
$PN"2"19;
%"RES"
"2","(-3100,3025)","0","mstr_discrete","I65";
;
CDS_SEC"1"
TOLERANCE"5%"
WATTAGE"1/16W"
PART_NUMBER"G21497-005"
PACK_TYPE"0402"
MATERIAL"CHIP"
$LOCATION"R771"
VALUE"0.0"
GROUP"PCIE_RISER"
SEC_TYPE"0402"
SEC"1"
CDS_LOCATION"R771"
CDS_LIB"mstr_discrete"
ROOM"PCIE_STEERING";
"A"
$PN"1"24;
"B"
$PN"2"69;
%"RES"
"2","(-3300,3375)","0","mstr_discrete","I66";
;
CDS_SEC"1"
MATERIAL"CHIP"
TOLERANCE"5%"
PACK_TYPE"0402"
GROUP"PCIE_RISER"
$LOCATION"R768"
VALUE"0.0"
WATTAGE"1/16W"
PART_NUMBER"G21497-005"
SEC"1"
SEC_TYPE"0402"
ROOM"PCIE_STEERING"
CDS_LIB"mstr_discrete"
CDS_LOCATION"R768";
"A"
$PN"1"48;
"B"
$PN"2"25;
%"TAP"
"3","(-3500,3575)","0","mstr_standard","I67";
;
CDS_LIB"mstr_standard"
BODY_TYPE"PLUMBING"
HDL_TAP"TRUE";
"B \NAC \NWC"4;
"S \NAC"
BN"15"68;
%"TAP"
"3","(-3300,3575)","0","mstr_standard","I68";
;
CDS_LIB"mstr_standard"
BODY_TYPE"PLUMBING"
HDL_TAP"TRUE";
"B \NAC \NWC"4;
"S \NAC"
BN"14"48;
%"TAP"
"3","(-3100,3575)","0","mstr_standard","I69";
;
CDS_LIB"mstr_standard"
BODY_TYPE"PLUMBING"
HDL_TAP"TRUE";
"B \NAC \NWC"4;
"S \NAC"
BN"13"24;
%"TAP"
"7","(-5125,1475)","0","mstr_standard","I7";
;
CDS_LIB"mstr_standard"
BODY_TYPE"PLUMBING"
HDL_TAP"TRUE";
"B \NAC \NWC"6;
"S \NAC"
BN"11"56;
%"TAP"
"7","(-3025,1475)","0","mstr_standard","I70";
;
CDS_LIB"mstr_standard"
BODY_TYPE"PLUMBING"
HDL_TAP"TRUE";
"B \NAC \NWC"5;
"S \NAC"
BN"13"59;
%"TAP"
"7","(-2825,1475)","0","mstr_standard","I71";
;
CDS_LIB"mstr_standard"
BODY_TYPE"PLUMBING"
HDL_TAP"TRUE";
"B \NAC \NWC"5;
"S \NAC"
BN"12"28;
%"RES"
"2","(-3025,1725)","0","mstr_discrete","I72";
;
CDS_SEC"1"
$LOCATION"R774"
TOLERANCE"5%"
VALUE"0.0"
PACK_TYPE"0402"
MATERIAL"CHIP"
WATTAGE"1/16W"
PART_NUMBER"G21497-005"
GROUP"PCIE_RISER"
CDS_LOCATION"R774"
CDS_LIB"mstr_discrete"
ROOM"PCIE_STEERING"
SEC"1"
SEC_TYPE"0402";
"A"
$PN"1"72;
"B"
$PN"2"59;
%"TAP"
"7","(-2625,1475)","0","mstr_standard","I73";
;
CDS_LIB"mstr_standard"
BODY_TYPE"PLUMBING"
HDL_TAP"TRUE";
"B \NAC \NWC"5;
"S \NAC"
BN"11"63;
%"RES"
"2","(-2625,1725)","0","mstr_discrete","I74";
;
CDS_SEC"1"
MATERIAL"CHIP"
$LOCATION"R779"
TOLERANCE"5%"
PART_NUMBER"G21497-005"
WATTAGE"1/16W"
PACK_TYPE"0402"
GROUP"PCIE_RISER"
VALUE"0.0"
CDS_LOCATION"R779"
CDS_LIB"mstr_discrete"
ROOM"PCIE_STEERING"
SEC"1"
SEC_TYPE"0402";
"A"
$PN"1"29;
"B"
$PN"2"63;
%"TAP"
"7","(-2425,1475)","0","mstr_standard","I75";
;
CDS_LIB"mstr_standard"
BODY_TYPE"PLUMBING"
HDL_TAP"TRUE";
"B \NAC \NWC"5;
"S \NAC"
BN"10"30;
%"TAP"
"7","(-2225,1475)","0","mstr_standard","I76";
;
CDS_LIB"mstr_standard"
BODY_TYPE"PLUMBING"
HDL_TAP"TRUE";
"B \NAC \NWC"5;
"S \NAC"
BN"9"17;
%"RES"
"2","(-2225,1725)","0","mstr_discrete","I77";
;
CDS_SEC"1"
TOLERANCE"5%"
VALUE"0.0"
$LOCATION"R783"
PACK_TYPE"0402"
WATTAGE"1/16W"
PART_NUMBER"G21497-005"
MATERIAL"CHIP"
GROUP"PCIE_RISER"
CDS_LOCATION"R783"
CDS_LIB"mstr_discrete"
ROOM"PCIE_STEERING"
SEC"1"
SEC_TYPE"0402";
"A"
$PN"1"65;
"B"
$PN"2"17;
%"TAP"
"7","(-2025,1475)","0","mstr_standard","I78";
;
CDS_LIB"mstr_standard"
BODY_TYPE"PLUMBING"
HDL_TAP"TRUE";
"B \NAC \NWC"5;
"S \NAC"
BN"8"66;
%"CAP"
"1","(-5125,1725)","2","mstr_discrete","I8";
;
CDS_SEC"1"
MATERIAL"X7R"
TOLERANCE"10%"
VOLTAGE"16V"
VALUE"0.22UF"
$LOCATION"C833"
PACK_TYPE"0402"
GROUP"PCIE_RISER"
PART_NUMBER"A36096-155"
CDS_LOCATION"C833"
CDS_LIB"mstr_discrete"
ROOM"OCP_STEERING"
SEC"1"
SEC_TYPE"0402";
"A"
$PN"1"54;
"B"
$PN"2"56;
%"RES"
"2","(-2825,2075)","0","mstr_discrete","I80";
;
CDS_SEC"1"
GROUP"PCIE_RISER"
WATTAGE"1/16W"
TOLERANCE"5%"
MATERIAL"CHIP"
$LOCATION"R777"
PART_NUMBER"G21497-005"
VALUE"0.0"
PACK_TYPE"0402"
CDS_LOCATION"R777"
CDS_LIB"mstr_discrete"
ROOM"PCIE_STEERING"
SEC"1"
SEC_TYPE"0402";
"A"
$PN"1"62;
"B"
$PN"2"28;
%"TAP"
"3","(-3025,2275)","0","mstr_standard","I81";
;
CDS_LIB"mstr_standard"
BODY_TYPE"PLUMBING"
HDL_TAP"TRUE";
"B \NAC \NWC"1;
"S \NAC"
BN"13"72;
%"TAP"
"3","(-2825,2275)","0","mstr_standard","I82";
;
CDS_LIB"mstr_standard"
BODY_TYPE"PLUMBING"
HDL_TAP"TRUE";
"B \NAC \NWC"1;
"S \NAC"
BN"12"62;
%"TAP"
"3","(-2625,2275)","0","mstr_standard","I83";
;
CDS_LIB"mstr_standard"
BODY_TYPE"PLUMBING"
HDL_TAP"TRUE";
"B \NAC \NWC"1;
"S \NAC"
BN"11"29;
%"TAP"
"7","(-2900,2775)","0","mstr_standard","I84";
;
CDS_LIB"mstr_standard"
BODY_TYPE"PLUMBING"
HDL_TAP"TRUE";
"B \NAC \NWC"2;
"S \NAC"
BN"12"9;
%"TAP"
"7","(-2700,2775)","0","mstr_standard","I85";
;
CDS_LIB"mstr_standard"
BODY_TYPE"PLUMBING"
HDL_TAP"TRUE";
"B \NAC \NWC"2;
"S \NAC"
BN"11"71;
%"RES"
"2","(-2425,2075)","0","mstr_discrete","I86";
;
CDS_SEC"1"
TOLERANCE"5%"
MATERIAL"CHIP"
WATTAGE"1/16W"
VALUE"0.0"
PACK_TYPE"0402"
PART_NUMBER"G21497-005"
$LOCATION"R781"
GROUP"PCIE_RISER"
CDS_LOCATION"R781"
CDS_LIB"mstr_discrete"
ROOM"PCIE_STEERING"
SEC"1"
SEC_TYPE"0402";
"A"
$PN"1"64;
"B"
$PN"2"30;
%"TAP"
"3","(-2425,2275)","0","mstr_standard","I87";
;
CDS_LIB"mstr_standard"
BODY_TYPE"PLUMBING"
HDL_TAP"TRUE";
"B \NAC \NWC"1;
"S \NAC"
BN"10"64;
%"TAP"
"3","(-2225,2275)","0","mstr_standard","I88";
;
CDS_LIB"mstr_standard"
BODY_TYPE"PLUMBING"
HDL_TAP"TRUE";
"B \NAC \NWC"1;
"S \NAC"
BN"9"65;
%"TAP"
"3","(-2025,2275)","0","mstr_standard","I89";
;
CDS_LIB"mstr_standard"
BODY_TYPE"PLUMBING"
HDL_TAP"TRUE";
"B \NAC \NWC"1;
"S \NAC"
BN"8"67;
%"TAP"
"7","(-2500,2775)","0","mstr_standard","I90";
;
HDL_TAP"TRUE"
BODY_TYPE"PLUMBING"
CDS_LIB"mstr_standard";
"B \NAC \NWC"2;
"S \NAC"
BN"10"20;
%"TAP"
"7","(-2300,2775)","0","mstr_standard","I91";
;
CDS_LIB"mstr_standard"
BODY_TYPE"PLUMBING"
HDL_TAP"TRUE";
"B \NAC \NWC"2;
"S \NAC"
BN"9"21;
%"TAP"
"7","(-2100,2775)","0","mstr_standard","I92";
;
CDS_LIB"mstr_standard"
BODY_TYPE"PLUMBING"
HDL_TAP"TRUE";
"B \NAC \NWC"2;
"S \NAC"
BN"8"22;
%"RES"
"2","(-2900,3375)","0","mstr_discrete","I93";
;
CDS_SEC"1"
WATTAGE"1/16W"
TOLERANCE"5%"
PACK_TYPE"0402"
PART_NUMBER"G21497-005"
MATERIAL"CHIP"
VALUE"0.0"
$LOCATION"R775"
GROUP"PCIE_RISER"
CDS_LOCATION"R775"
CDS_LIB"mstr_discrete"
ROOM"PCIE_STEERING"
SEC_TYPE"0402"
SEC"1";
"A"
$PN"1"50;
"B"
$PN"2"9;
%"RES"
"2","(-2700,3025)","0","mstr_discrete","I94";
;
CDS_SEC"1"
GROUP"PCIE_RISER"
WATTAGE"1/16W"
PART_NUMBER"G21497-005"
MATERIAL"CHIP"
TOLERANCE"5%"
VALUE"0.0"
$LOCATION"R778"
PACK_TYPE"0402"
SEC_TYPE"0402"
SEC"1"
CDS_LOCATION"R778"
CDS_LIB"mstr_discrete"
ROOM"PCIE_STEERING";
"A"
$PN"1"27;
"B"
$PN"2"71;
%"TAP"
"3","(-2900,3575)","0","mstr_standard","I95";
;
CDS_LIB"mstr_standard"
BODY_TYPE"PLUMBING"
HDL_TAP"TRUE";
"B \NAC \NWC"4;
"S \NAC"
BN"12"50;
%"TAP"
"3","(-2700,3575)","0","mstr_standard","I96";
;
CDS_LIB"mstr_standard"
BODY_TYPE"PLUMBING"
HDL_TAP"TRUE";
"B \NAC \NWC"4;
"S \NAC"
BN"11"27;
%"RES"
"2","(-2500,3375)","0","mstr_discrete","I97";
;
CDS_SEC"1"
PART_NUMBER"G21497-005"
MATERIAL"CHIP"
TOLERANCE"5%"
$LOCATION"R780"
PACK_TYPE"0402"
WATTAGE"1/16W"
VALUE"0.0"
GROUP"PCIE_RISER"
SEC_TYPE"0402"
SEC"1"
ROOM"PCIE_STEERING"
CDS_LIB"mstr_discrete"
CDS_LOCATION"R780";
"A"
$PN"1"49;
"B"
$PN"2"20;
%"RES"
"2","(-2300,3025)","0","mstr_discrete","I98";
;
CDS_SEC"1"
VALUE"0.0"
PART_NUMBER"G21497-005"
TOLERANCE"5%"
WATTAGE"1/16W"
MATERIAL"CHIP"
$LOCATION"R782"
PACK_TYPE"0402"
GROUP"PCIE_RISER"
SEC_TYPE"0402"
SEC"1"
CDS_LOCATION"R782"
CDS_LIB"mstr_discrete"
ROOM"PCIE_STEERING";
"A"
$PN"1"23;
"B"
$PN"2"21;
%"RES"
"2","(-2100,3375)","0","mstr_discrete","I99";
;
CDS_SEC"1"
VALUE"0.0"
TOLERANCE"5%"
WATTAGE"1/16W"
MATERIAL"CHIP"
GROUP"PCIE_RISER"
$LOCATION"R784"
PART_NUMBER"G21497-005"
PACK_TYPE"0402"
SEC"1"
SEC_TYPE"0402"
ROOM"PCIE_STEERING"
CDS_LIB"mstr_discrete"
CDS_LOCATION"R784";
"A"
$PN"1"26;
"B"
$PN"2"22;
END.
